# BASEBOARD_FAB2 (Tioga Pass) — schematic netlist excerpt (pin names and nets, part order shuffled) for the footprints in the layout excerpt that follows; sources: Cadence DE-HDL packaged netlist, KiCad conversion of Wiwynn_Tioga_Pass_MB.brd

EU4G1  NCP3232L  IC  pkg SM  page 233
  SS  = VR_PVPP_GHJ_SS
  FB  = VR_FB_PVPP_GHJ
  COMP  = VR_COMP_PVPP_GHJ_3
  ISET  = VR_PVPP_GHJ_ISET
  AGND  = AGND_PVPP_GHJ
  OTS  = AGND_PVPP_GHJ
  PG  = PWRGD_PVPP_GHJ_R
  VIN(0)  = VR_FET_SW_P12V_STBY_PVPP_GHJ
  VIN(1)  = VR_FET_SW_P12V_STBY_PVPP_GHJ
  VIN(2)  = VR_FET_SW_P12V_STBY_PVPP_GHJ
  VIN(3)  = VR_FET_SW_P12V_STBY_PVPP_GHJ
  VIN(4)  = VR_FET_SW_P12V_STBY_PVPP_GHJ
  VIN(5)  = VR_FET_SW_P12V_STBY_PVPP_GHJ
  VIN(6)  = VR_FET_SW_P12V_STBY_PVPP_GHJ
  VSWH(0)  = VR_PVPP_GHJ_PHASE
  PGND(0)  = GND
  PGND(1)  = GND
  PGND(2)  = GND
  PGND(3)  = GND
  PGND(4)  = GND
  PGND(5)  = GND
  PGND(6)  = GND
  PGND(7)  = GND
  PGND(8)  = GND
  PGND(9)  = GND
  PGND(10)  = GND
  PGND(11)  = GND
  PGND(12)  = GND
  VSWH(1)  = VR_PVPP_GHJ_PHASE
  VSWH(2)  = VR_PVPP_GHJ_PHASE
  VSWH(3)  = VR_PVPP_GHJ_PHASE
  VSWH(4)  = VR_PVPP_GHJ_PHASE
  VSWH(5)  = VR_PVPP_GHJ_PHASE
  VSWH(6)  = VR_PVPP_GHJ_PHASE
  VSW  = VR_PVPP_GHJ_PHASE
  BST  = VR_PVPP_GHJ_BOOT
  PGND(13)  = GND
  VB  = VR_VB_PVPP_GHJ
  VCC  = VR_FET_SW_P12V_STBY_PVPP_GHJ
  EN  = FM_PVPP_PVDDQ_CPU1_EN_GHJ
  GND  = GND
  VIN(7)  = VR_FET_SW_P12V_STBY_PVPP_GHJ
  VSWH(7)  = VR_PVPP_GHJ_PHASE

(kicad_pcb
	(version 20260206)
	(generator "pcbnew")
	(generator_version "10.0")
	(general
		(thickness 1.6)
		(legacy_teardrops no)
	)
	(paper "A4")
	(title_block
		(title "Wiwynn_Tioga_Pass_MB.brd")
		(comment 1 "Tioga Pass / footprint 1232 of 4770 (EU4G1), pads 18-35 of 43")
	)
	(layers
		(0 "F.Cu" signal "TOP")
		(4 "In1.Cu" signal "L2GND")
		(6 "In2.Cu" signal "L3")
		(8 "In3.Cu" signal "L4GND")
		(10 "In4.Cu" signal "L5")
		(12 "In5.Cu" signal "L6GND")
		(14 "In6.Cu" signal "L7VCC")
		(16 "In7.Cu" signal "L8VCC")
		(18 "In8.Cu" signal "L9GND")
		(20 "In9.Cu" signal "L10")
		(22 "In10.Cu" signal "L11GND")
		(24 "In11.Cu" signal "L12")
		(26 "In12.Cu" signal "L13GND")
		(2 "B.Cu" signal "BOTTOM")
		(9 "F.Adhes" user "F.Adhesive")
		(11 "B.Adhes" user "B.Adhesive")
		(13 "F.Paste" user "Package Geometry/Pastemask Top")
		(15 "B.Paste" user "Package Geometry/Pastemask Bottom")
		(5 "F.SilkS" user "Ref Des/Silkscreen Top")
		(7 "B.SilkS" user "Ref Des/Silkscreen Bottom")
		(1 "F.Mask" user "Board Geometry/Soldermask Top")
		(3 "B.Mask" user "Board Geometry/Soldermask Bottom")
		(17 "Dwgs.User" user "User.Drawings")
		(19 "Cmts.User" user "User.Comments")
		(21 "Eco1.User" user "User.Eco1")
		(23 "Eco2.User" user "User.Eco2")
		(25 "Edge.Cuts" user "Board Geometry/Outline")
		(27 "Margin" user)
		(31 "F.CrtYd" user "Package Geometry/Place Bound Top")
		(29 "B.CrtYd" user "Package Geometry/Place Bound Bottom")
		(35 "F.Fab" user "Ref Des/Assembly Top")
		(33 "B.Fab" user "Ref Des/Assembly Bottom")
	)
	(footprint ""
		(layer "F.Cu")
		(at 177.673 -13.335 90)
		(property "Reference" "EU4G1"
			(at 5.18033 -0.889 0)
			(unlocked yes)
			(layer "F.SilkS")
			(effects
				(font
					(size 0.7874 0.5842)
					(thickness 0.1524)
				)
				(justify left)
			)
		)
		(property "Value" ""
			(at 0 0 90)
			(layer "F.Fab")
			(effects
				(font
					(size 1.27 1.27)
				)
			)
		)
		(duplicate_pad_numbers_are_jumpers no)
		(pad "18" smd custom
			(at 1.249934 2.8321 90)
			(size 0.06985 0.06985)
			(layers "F.Cu" "F.Mask" "F.Paste")
			(net "GND")
			(options
				(clearance outline)
				(anchor circle)
			)
			(primitives
				(gr_poly
					(pts
						(arc
							(start -0.1397 -0.2413)
							(mid 0 -0.381)
							(end 0.1397 -0.2413)
						)
						(xy 0.1397 0.381) (xy -0.1397 0.381)
					)
					(width 0)
					(fill yes)
				)
			)
		)
		(pad "19" smd custom
			(at 1.75006 2.8321 90)
			(size 0.06985 0.06985)
			(layers "F.Cu" "F.Mask" "F.Paste")
			(net "GND")
			(options
				(clearance outline)
				(anchor circle)
			)
			(primitives
				(gr_poly
					(pts
						(arc
							(start -0.1397 -0.2413)
							(mid 0 -0.381)
							(end 0.1397 -0.2413)
						)
						(xy 0.1397 0.381) (xy -0.1397 0.381)
					)
					(width 0)
					(fill yes)
				)
			)
		)
		(pad "20" smd custom
			(at 2.249932 2.8321 90)
			(size 0.06985 0.06985)
			(layers "F.Cu" "F.Mask" "F.Paste")
			(net "GND")
			(options
				(clearance outline)
				(anchor circle)
			)
			(primitives
				(gr_poly
					(pts
						(arc
							(start -0.1397 -0.2413)
							(mid 0 -0.381)
							(end 0.1397 -0.2413)
						)
						(xy 0.1397 0.381) (xy -0.1397 0.381)
					)
					(width 0)
					(fill yes)
				)
			)
		)
		(pad "21" smd custom
			(at 2.8321 2.249932 90)
			(size 0.06985 0.06985)
			(layers "F.Cu" "F.Mask" "F.Paste")
			(net "GND")
			(options
				(clearance outline)
				(anchor circle)
			)
			(primitives
				(gr_poly
					(pts
						(arc
							(start -0.2413 0.1397)
							(mid -0.381 0)
							(end -0.2413 -0.1397)
						)
						(xy 0.381 -0.1397) (xy 0.381 0.1397)
					)
					(width 0)
					(fill yes)
				)
			)
		)
		(pad "22" smd custom
			(at 2.8321 1.75006 90)
			(size 0.06985 0.06985)
			(layers "F.Cu" "F.Mask" "F.Paste")
			(net "GND")
			(options
				(clearance outline)
				(anchor circle)
			)
			(primitives
				(gr_poly
					(pts
						(arc
							(start -0.2413 0.1397)
							(mid -0.381 0)
							(end -0.2413 -0.1397)
						)
						(xy 0.381 -0.1397) (xy 0.381 0.1397)
					)
					(width 0)
					(fill yes)
				)
			)
		)
		(pad "23" smd custom
			(at 2.8321 1.249934 90)
			(size 0.06985 0.06985)
			(layers "F.Cu" "F.Mask" "F.Paste")
			(net "GND")
			(options
				(clearance outline)
				(anchor circle)
			)
			(primitives
				(gr_poly
					(pts
						(arc
							(start -0.2413 0.1397)
							(mid -0.381 0)
							(end -0.2413 -0.1397)
						)
						(xy 0.381 -0.1397) (xy 0.381 0.1397)
					)
					(width 0)
					(fill yes)
				)
			)
		)
		(pad "24" smd custom
			(at 2.8321 0.750062 90)
			(size 0.06985 0.06985)
			(layers "F.Cu" "F.Mask" "F.Paste")
			(net "GND")
			(options
				(clearance outline)
				(anchor circle)
			)
			(primitives
				(gr_poly
					(pts
						(arc
							(start -0.2413 0.1397)
							(mid -0.381 0)
							(end -0.2413 -0.1397)
						)
						(xy 0.381 -0.1397) (xy 0.381 0.1397)
					)
					(width 0)
					(fill yes)
				)
			)
		)
		(pad "25" smd custom
			(at 2.8321 0.249936 90)
			(size 0.06985 0.06985)
			(layers "F.Cu" "F.Mask" "F.Paste")
			(net "GND")
			(options
				(clearance outline)
				(anchor circle)
			)
			(primitives
				(gr_poly
					(pts
						(arc
							(start -0.2413 0.1397)
							(mid -0.381 0)
							(end -0.2413 -0.1397)
						)
						(xy 0.381 -0.1397) (xy 0.381 0.1397)
					)
					(width 0)
					(fill yes)
				)
			)
		)
		(pad "26" smd custom
			(at 2.8321 -0.249936 90)
			(size 0.06985 0.06985)
			(layers "F.Cu" "F.Mask" "F.Paste")
			(net "GND")
			(options
				(clearance outline)
				(anchor circle)
			)
			(primitives
				(gr_poly
					(pts
						(arc
							(start -0.2413 0.1397)
							(mid -0.381 0)
							(end -0.2413 -0.1397)
						)
						(xy 0.381 -0.1397) (xy 0.381 0.1397)
					)
					(width 0)
					(fill yes)
				)
			)
		)
		(pad "27" smd custom
			(at 2.8321 -0.750062 90)
			(size 0.06985 0.06985)
			(layers "F.Cu" "F.Mask" "F.Paste")
			(net "GND")
			(options
				(clearance outline)
				(anchor circle)
			)
			(primitives
				(gr_poly
					(pts
						(arc
							(start -0.2413 0.1397)
							(mid -0.381 0)
							(end -0.2413 -0.1397)
						)
						(xy 0.381 -0.1397) (xy 0.381 0.1397)
					)
					(width 0)
					(fill yes)
				)
			)
		)
		(pad "28" smd custom
			(at 2.8321 -1.249934 90)
			(size 0.06985 0.06985)
			(layers "F.Cu" "F.Mask" "F.Paste")
			(net "GND")
			(options
				(clearance outline)
				(anchor circle)
			)
			(primitives
				(gr_poly
					(pts
						(arc
							(start -0.2413 0.1397)
							(mid -0.381 0)
							(end -0.2413 -0.1397)
						)
						(xy 0.381 -0.1397) (xy 0.381 0.1397)
					)
					(width 0)
					(fill yes)
				)
			)
		)
		(pad "29" smd custom
			(at 2.8321 -1.75006 90)
			(size 0.06985 0.06985)
			(layers "F.Cu" "F.Mask" "F.Paste")
			(net "VR_PVPP_GHJ_PHASE")
			(options
				(clearance outline)
				(anchor circle)
			)
			(primitives
				(gr_poly
					(pts
						(arc
							(start -0.2413 0.1397)
							(mid -0.381 0)
							(end -0.2413 -0.1397)
						)
						(xy 0.381 -0.1397) (xy 0.381 0.1397)
					)
					(width 0)
					(fill yes)
				)
			)
		)
		(pad "30" smd custom
			(at 2.8321 -2.249932 90)
			(size 0.06985 0.06985)
			(layers "F.Cu" "F.Mask" "F.Paste")
			(net "VR_PVPP_GHJ_PHASE")
			(options
				(clearance outline)
				(anchor circle)
			)
			(primitives
				(gr_poly
					(pts
						(arc
							(start -0.2413 0.1397)
							(mid -0.381 0)
							(end -0.2413 -0.1397)
						)
						(xy 0.381 -0.1397) (xy 0.381 0.1397)
					)
					(width 0)
					(fill yes)
				)
			)
		)
		(pad "31" smd custom
			(at 2.249932 -2.8321 90)
			(size 0.06985 0.06985)
			(layers "F.Cu" "F.Mask" "F.Paste")
			(net "VR_PVPP_GHJ_PHASE")
			(options
				(clearance outline)
				(anchor circle)
			)
			(primitives
				(gr_poly
					(pts
						(arc
							(start 0.1397 0.2413)
							(mid 0 0.381)
							(end -0.1397 0.2413)
						)
						(xy -0.1397 -0.381) (xy 0.1397 -0.381)
					)
					(width 0)
					(fill yes)
				)
			)
		)
		(pad "32" smd custom
			(at 1.75006 -2.8321 90)
			(size 0.06985 0.06985)
			(layers "F.Cu" "F.Mask" "F.Paste")
			(net "VR_PVPP_GHJ_PHASE")
			(options
				(clearance outline)
				(anchor circle)
			)
			(primitives
				(gr_poly
					(pts
						(arc
							(start 0.1397 0.2413)
							(mid 0 0.381)
							(end -0.1397 0.2413)
						)
						(xy -0.1397 -0.381) (xy 0.1397 -0.381)
					)
					(width 0)
					(fill yes)
				)
			)
		)
		(pad "33" smd custom
			(at 1.249934 -2.8321 90)
			(size 0.06985 0.06985)
			(layers "F.Cu" "F.Mask" "F.Paste")
			(net "VR_PVPP_GHJ_PHASE")
			(options
				(clearance outline)
				(anchor circle)
			)
			(primitives
				(gr_poly
					(pts
						(arc
							(start 0.1397 0.2413)
							(mid 0 0.381)
							(end -0.1397 0.2413)
						)
						(xy -0.1397 -0.381) (xy 0.1397 -0.381)
					)
					(width 0)
					(fill yes)
				)
			)
		)
		(pad "34" smd custom
			(at 0.750062 -2.8321 90)
			(size 0.06985 0.06985)
			(layers "F.Cu" "F.Mask" "F.Paste")
			(net "VR_PVPP_GHJ_PHASE")
			(options
				(clearance outline)
				(anchor circle)
			)
			(primitives
				(gr_poly
					(pts
						(arc
							(start 0.1397 0.2413)
							(mid 0 0.381)
							(end -0.1397 0.2413)
						)
						(xy -0.1397 -0.381) (xy 0.1397 -0.381)
					)
					(width 0)
					(fill yes)
				)
			)
		)
		(pad "35" smd custom
			(at 0.249936 -2.8321 90)
			(size 0.06985 0.06985)
			(layers "F.Cu" "F.Mask" "F.Paste")
			(net "VR_PVPP_GHJ_PHASE")
			(options
				(clearance outline)
				(anchor circle)
			)
			(primitives
				(gr_poly
					(pts
						(arc
							(start 0.1397 0.2413)
							(mid 0 0.381)
							(end -0.1397 0.2413)
						)
						(xy -0.1397 -0.381) (xy 0.1397 -0.381)
					)
					(width 0)
					(fill yes)
				)
			)
		)
	)
)
